(kicad_pcb
	(version 20260206)
	(generator "pcbnew")
	(generator_version "10.0")
	(general
		(thickness 1.6)
		(legacy_teardrops no)
	)
	(paper "A4")
	(title_block
		(title "01162023_DA0F0TEBIF0_F0T_Expander_BD_F_brd_V02_OCP.brd")
		(comment 1 "Grand Teton / footprints 5704-5707 of 9728")
	)
	(layers
		(0 "F.Cu" signal "TOP")
		(4 "In1.Cu" signal "GND")
		(6 "In2.Cu" signal "VCC")
		(8 "In3.Cu" signal "VCC1")
		(10 "In4.Cu" signal "GND1")
		(12 "In5.Cu" signal "IN1")
		(14 "In6.Cu" signal "GND2")
		(16 "In7.Cu" signal "IN2")
		(18 "In8.Cu" signal "GND3")
		(20 "In9.Cu" signal "IN3")
		(22 "In10.Cu" signal "GND4")
		(24 "In11.Cu" signal "IN4")
		(26 "In12.Cu" signal "GND5")
		(28 "In13.Cu" signal "IN5")
		(30 "In14.Cu" signal "GND6")
		(32 "In15.Cu" signal "IN6")
		(34 "In16.Cu" signal "GND7")
		(2 "B.Cu" signal "BOTTOM")
		(9 "F.Adhes" user "F.Adhesive")
		(11 "B.Adhes" user "B.Adhesive")
		(13 "F.Paste" user "Package Geometry/Pastemask Top")
		(15 "B.Paste" user "Package Geometry/Pastemask Bottom")
		(5 "F.SilkS" user "Ref Des/Silkscreen Top")
		(7 "B.SilkS" user "Ref Des/Silkscreen Bottom")
		(1 "F.Mask" user "Board Geometry/Soldermask Top")
		(3 "B.Mask" user "Board Geometry/Soldermask Bottom")
		(17 "Dwgs.User" user "User.Drawings")
		(19 "Cmts.User" user "User.Comments")
		(21 "Eco1.User" user "User.Eco1")
		(23 "Eco2.User" user "User.Eco2")
		(25 "Edge.Cuts" user "Board Geometry/Outline")
		(27 "Margin" user)
		(31 "F.CrtYd" user "Package Geometry/Place Bound Top")
		(29 "B.CrtYd" user "Package Geometry/Place Bound Bottom")
		(35 "F.Fab" user "Ref Des/Assembly Top")
		(33 "B.Fab" user "Ref Des/Assembly Bottom")
	)
	(footprint ""
		(layer "F.Cu")
		(at 395.590014 -72.766682 90)
		(property "Reference" "PR7090"
			(at 0 0 90)
			(layer "F.SilkS")
			(hide yes)
			(effects
				(font
					(size 1.27 1.27)
				)
			)
		)
		(property "Value" ""
			(at 0 0 90)
			(layer "F.Fab")
			(effects
				(font
					(size 1.27 1.27)
				)
			)
		)
		(duplicate_pad_numbers_are_jumpers no)
		(fp_line
			(start 0.7874 -0.4064)
			(end 0.7874 0.4064)
			(stroke
				(width 0.1524)
				(type default)
			)
			(layer "F.SilkS")
		)
		(fp_line
			(start -0.7874 -0.4064)
			(end 0.7874 -0.4064)
			(stroke
				(width 0.1524)
				(type default)
			)
			(layer "F.SilkS")
		)
		(fp_line
			(start 0.7874 0.4064)
			(end -0.7874 0.4064)
			(stroke
				(width 0.1524)
				(type default)
			)
			(layer "F.SilkS")
		)
		(fp_line
			(start -0.7874 0.4064)
			(end -0.7874 -0.4064)
			(stroke
				(width 0.1524)
				(type default)
			)
			(layer "F.SilkS")
		)
		(fp_line
			(start -0.12065 -0.305054)
			(end -0.12065 -0.2794)
			(stroke
				(width 0.1)
				(type default)
			)
			(layer "F.Fab")
		)
		(fp_line
			(start -0.67945 -0.305054)
			(end -0.12065 -0.305054)
			(stroke
				(width 0.1)
				(type default)
			)
			(layer "F.Fab")
		)
		(fp_line
			(start 0.67945 -0.3048)
			(end 0.67945 0.3048)
			(stroke
				(width 0.1)
				(type default)
			)
			(layer "F.Fab")
		)
		(fp_line
			(start 0.12065 -0.3048)
			(end 0.67945 -0.3048)
			(stroke
				(width 0.1)
				(type default)
			)
			(layer "F.Fab")
		)
		(fp_line
			(start 0.12065 -0.2794)
			(end 0.12065 -0.3048)
			(stroke
				(width 0.1)
				(type default)
			)
			(layer "F.Fab")
		)
		(fp_line
			(start -0.12065 -0.2794)
			(end 0.12065 -0.2794)
			(stroke
				(width 0.1)
				(type default)
			)
			(layer "F.Fab")
		)
		(fp_line
			(start 0.120396 0.2794)
			(end -0.12065 0.2794)
			(stroke
				(width 0.1)
				(type default)
			)
			(layer "F.Fab")
		)
		(fp_line
			(start -0.12065 0.2794)
			(end -0.12065 0.3048)
			(stroke
				(width 0.1)
				(type default)
			)
			(layer "F.Fab")
		)
		(fp_line
			(start 0.67945 0.3048)
			(end 0.120396 0.3048)
			(stroke
				(width 0.1)
				(type default)
			)
			(layer "F.Fab")
		)
		(fp_line
			(start 0.120396 0.3048)
			(end 0.120396 0.2794)
			(stroke
				(width 0.1)
				(type default)
			)
			(layer "F.Fab")
		)
		(fp_line
			(start -0.12065 0.3048)
			(end -0.67945 0.3048)
			(stroke
				(width 0.1)
				(type default)
			)
			(layer "F.Fab")
		)
		(fp_line
			(start -0.67945 0.3048)
			(end -0.67945 -0.305054)
			(stroke
				(width 0.1)
				(type default)
			)
			(layer "F.Fab")
		)
		(pad "1" smd circle
			(at -0.40005 0 90)
			(size 0 0)
			(layers "F.Cu" "F.Mask" "F.Paste")
			(net "P12V_SSD13_CO_ILIMIT")
		)
		(pad "2" smd circle
			(at 0.40005 0 90)
			(size 0 0)
			(layers "F.Cu" "F.Mask" "F.Paste")
			(net "GND")
		)
	)
	(footprint ""
		(layer "F.Cu")
		(at 57.294018 -34.248852)
		(property "Reference" "R5660"
			(at 0 0 0)
			(layer "F.SilkS")
			(hide yes)
			(effects
				(font
					(size 1.27 1.27)
				)
			)
		)
		(property "Value" ""
			(at 0 0 0)
			(layer "F.Fab")
			(effects
				(font
					(size 1.27 1.27)
				)
			)
		)
		(duplicate_pad_numbers_are_jumpers no)
		(fp_line
			(start -0.7874 -0.4064)
			(end 0.7874 -0.4064)
			(stroke
				(width 0.1524)
				(type default)
			)
			(layer "F.SilkS")
		)
		(fp_line
			(start -0.7874 0.4064)
			(end -0.7874 -0.4064)
			(stroke
				(width 0.1524)
				(type default)
			)
			(layer "F.SilkS")
		)
		(fp_line
			(start 0.7874 -0.4064)
			(end 0.7874 0.4064)
			(stroke
				(width 0.1524)
				(type default)
			)
			(layer "F.SilkS")
		)
		(fp_line
			(start 0.7874 0.4064)
			(end -0.7874 0.4064)
			(stroke
				(width 0.1524)
				(type default)
			)
			(layer "F.SilkS")
		)
		(fp_line
			(start -0.67945 -0.305054)
			(end -0.12065 -0.305054)
			(stroke
				(width 0.1)
				(type default)
			)
			(layer "F.Fab")
		)
		(fp_line
			(start -0.67945 0.3048)
			(end -0.67945 -0.305054)
			(stroke
				(width 0.1)
				(type default)
			)
			(layer "F.Fab")
		)
		(fp_line
			(start -0.12065 -0.305054)
			(end -0.12065 -0.2794)
			(stroke
				(width 0.1)
				(type default)
			)
			(layer "F.Fab")
		)
		(fp_line
			(start -0.12065 -0.2794)
			(end 0.12065 -0.2794)
			(stroke
				(width 0.1)
				(type default)
			)
			(layer "F.Fab")
		)
		(fp_line
			(start -0.12065 0.2794)
			(end -0.12065 0.3048)
			(stroke
				(width 0.1)
				(type default)
			)
			(layer "F.Fab")
		)
		(fp_line
			(start -0.12065 0.3048)
			(end -0.67945 0.3048)
			(stroke
				(width 0.1)
				(type default)
			)
			(layer "F.Fab")
		)
		(fp_line
			(start 0.120396 0.2794)
			(end -0.12065 0.2794)
			(stroke
				(width 0.1)
				(type default)
			)
			(layer "F.Fab")
		)
		(fp_line
			(start 0.120396 0.3048)
			(end 0.120396 0.2794)
			(stroke
				(width 0.1)
				(type default)
			)
			(layer "F.Fab")
		)
		(fp_line
			(start 0.12065 -0.3048)
			(end 0.67945 -0.3048)
			(stroke
				(width 0.1)
				(type default)
			)
			(layer "F.Fab")
		)
		(fp_line
			(start 0.12065 -0.2794)
			(end 0.12065 -0.3048)
			(stroke
				(width 0.1)
				(type default)
			)
			(layer "F.Fab")
		)
		(fp_line
			(start 0.67945 -0.3048)
			(end 0.67945 0.3048)
			(stroke
				(width 0.1)
				(type default)
			)
			(layer "F.Fab")
		)
		(fp_line
			(start 0.67945 0.3048)
			(end 0.120396 0.3048)
			(stroke
				(width 0.1)
				(type default)
			)
			(layer "F.Fab")
		)
		(pad "1" smd circle
			(at -0.40005 0)
			(size 0 0)
			(layers "F.Cu" "F.Mask" "F.Paste")
			(net "RST_SMB_SSD2_ISO_N")
		)
		(pad "2" smd circle
			(at 0.40005 0)
			(size 0 0)
			(layers "F.Cu" "F.Mask" "F.Paste")
			(net "P3V3_SSD2")
		)
	)
	(footprint ""
		(layer "F.Cu")
		(at 215.075516 -122.525028)
		(property "Reference" "C2883"
			(at 0 0 0)
			(layer "F.SilkS")
			(hide yes)
			(effects
				(font
					(size 1.27 1.27)
				)
			)
		)
		(property "Value" ""
			(at 0 0 0)
			(layer "F.Fab")
			(effects
				(font
					(size 1.27 1.27)
				)
			)
		)
		(duplicate_pad_numbers_are_jumpers no)
		(fp_line
			(start -0.7874 -0.4064)
			(end 0.7874 -0.4064)
			(stroke
				(width 0.1524)
				(type default)
			)
			(layer "F.SilkS")
		)
		(fp_line
			(start -0.7874 0.4064)
			(end -0.7874 -0.4064)
			(stroke
				(width 0.1524)
				(type default)
			)
			(layer "F.SilkS")
		)
		(fp_line
			(start 0.7874 -0.4064)
			(end 0.7874 0.4064)
			(stroke
				(width 0.1524)
				(type default)
			)
			(layer "F.SilkS")
		)
		(fp_line
			(start 0.7874 0.4064)
			(end -0.7874 0.4064)
			(stroke
				(width 0.1524)
				(type default)
			)
			(layer "F.SilkS")
		)
		(fp_line
			(start -0.67945 -0.305054)
			(end -0.12065 -0.305054)
			(stroke
				(width 0.1)
				(type default)
			)
			(layer "F.Fab")
		)
		(fp_line
			(start -0.67945 0.3048)
			(end -0.67945 -0.305054)
			(stroke
				(width 0.1)
				(type default)
			)
			(layer "F.Fab")
		)
		(fp_line
			(start -0.12065 -0.305054)
			(end -0.12065 -0.2794)
			(stroke
				(width 0.1)
				(type default)
			)
			(layer "F.Fab")
		)
		(fp_line
			(start -0.12065 -0.2794)
			(end 0.12065 -0.2794)
			(stroke
				(width 0.1)
				(type default)
			)
			(layer "F.Fab")
		)
		(fp_line
			(start -0.12065 0.2794)
			(end -0.12065 0.3048)
			(stroke
				(width 0.1)
				(type default)
			)
			(layer "F.Fab")
		)
		(fp_line
			(start -0.12065 0.3048)
			(end -0.67945 0.3048)
			(stroke
				(width 0.1)
				(type default)
			)
			(layer "F.Fab")
		)
		(fp_line
			(start 0.120396 0.2794)
			(end -0.12065 0.2794)
			(stroke
				(width 0.1)
				(type default)
			)
			(layer "F.Fab")
		)
		(fp_line
			(start 0.120396 0.3048)
			(end 0.120396 0.2794)
			(stroke
				(width 0.1)
				(type default)
			)
			(layer "F.Fab")
		)
		(fp_line
			(start 0.12065 -0.3048)
			(end 0.67945 -0.3048)
			(stroke
				(width 0.1)
				(type default)
			)
			(layer "F.Fab")
		)
		(fp_line
			(start 0.12065 -0.2794)
			(end 0.12065 -0.3048)
			(stroke
				(width 0.1)
				(type default)
			)
			(layer "F.Fab")
		)
		(fp_line
			(start 0.67945 -0.3048)
			(end 0.67945 0.3048)
			(stroke
				(width 0.1)
				(type default)
			)
			(layer "F.Fab")
		)
		(fp_line
			(start 0.67945 0.3048)
			(end 0.120396 0.3048)
			(stroke
				(width 0.1)
				(type default)
			)
			(layer "F.Fab")
		)
		(pad "1" smd circle
			(at -0.40005 0)
			(size 0 0)
			(layers "F.Cu" "F.Mask" "F.Paste")
			(net "HP_NIC3_EN")
		)
		(pad "2" smd circle
			(at 0.40005 0)
			(size 0 0)
			(layers "F.Cu" "F.Mask" "F.Paste")
			(net "GND")
		)
	)
	(footprint ""
		(layer "F.Cu")
		(at 26.57856 -308.611524 45)
		(property "Reference" "R4360"
			(at 0 0 45)
			(layer "F.SilkS")
			(hide yes)
			(effects
				(font
					(size 1.27 1.27)
				)
			)
		)
		(property "Value" ""
			(at 0 0 45)
			(layer "F.Fab")
			(effects
				(font
					(size 1.27 1.27)
				)
			)
		)
		(duplicate_pad_numbers_are_jumpers no)
		(fp_line
			(start -0.787389 -0.406267)
			(end 0.787389 -0.406267)
			(stroke
				(width 0.1524)
				(type default)
			)
			(layer "F.SilkS")
		)
		(fp_line
			(start -0.787389 0.406267)
			(end -0.787389 -0.406267)
			(stroke
				(width 0.1524)
				(type default)
			)
			(layer "F.SilkS")
		)
		(fp_line
			(start 0.787389 -0.406267)
			(end 0.787389 0.406267)
			(stroke
				(width 0.1524)
				(type default)
			)
			(layer "F.SilkS")
		)
		(fp_line
			(start 0.787389 0.406267)
			(end -0.787389 0.406267)
			(stroke
				(width 0.1524)
				(type default)
			)
			(layer "F.SilkS")
		)
		(fp_line
			(start -0.679446 -0.305149)
			(end -0.120695 -0.304969)
			(stroke
				(width 0.1)
				(type default)
			)
			(layer "F.Fab")
		)
		(fp_line
			(start -0.120695 -0.304969)
			(end -0.120695 -0.279466)
			(stroke
				(width 0.1)
				(type default)
			)
			(layer "F.Fab")
		)
		(fp_line
			(start -0.120695 -0.279466)
			(end 0.120695 -0.279466)
			(stroke
				(width 0.1)
				(type default)
			)
			(layer "F.Fab")
		)
		(fp_line
			(start -0.679446 0.30479)
			(end -0.679446 -0.305149)
			(stroke
				(width 0.1)
				(type default)
			)
			(layer "F.Fab")
		)
		(fp_line
			(start 0.120515 -0.30479)
			(end 0.679446 -0.30479)
			(stroke
				(width 0.1)
				(type default)
			)
			(layer "F.Fab")
		)
		(fp_line
			(start 0.120695 -0.279466)
			(end 0.120515 -0.30479)
			(stroke
				(width 0.1)
				(type default)
			)
			(layer "F.Fab")
		)
		(fp_line
			(start -0.120695 0.279466)
			(end -0.120515 0.30479)
			(stroke
				(width 0.1)
				(type default)
			)
			(layer "F.Fab")
		)
		(fp_line
			(start -0.120515 0.30479)
			(end -0.679446 0.30479)
			(stroke
				(width 0.1)
				(type default)
			)
			(layer "F.Fab")
		)
		(fp_line
			(start 0.679446 -0.30479)
			(end 0.679446 0.30479)
			(stroke
				(width 0.1)
				(type default)
			)
			(layer "F.Fab")
		)
		(fp_line
			(start 0.120335 0.279466)
			(end -0.120695 0.279466)
			(stroke
				(width 0.1)
				(type default)
			)
			(layer "F.Fab")
		)
		(fp_line
			(start 0.120515 0.30479)
			(end 0.120335 0.279466)
			(stroke
				(width 0.1)
				(type default)
			)
			(layer "F.Fab")
		)
		(fp_line
			(start 0.679446 0.30479)
			(end 0.120515 0.30479)
			(stroke
				(width 0.1)
				(type default)
			)
			(layer "F.Fab")
		)
		(pad "1" smd circle
			(at -0.40005 0 45)
			(size 0 0)
			(layers "F.Cu" "F.Mask" "F.Paste")
			(net "P1V8_PEX")
		)
		(pad "2" smd circle
			(at 0.40005 0 45)
			(size 0 0)
			(layers "F.Cu" "F.Mask" "F.Paste")
			(net "IRQ_PEX0_CLKREQ_INT_N")
		)
	)
)
